(kicad_pcb
	(version 20241229)
	(generator "pcbnew")
	(generator_version "9.0")
	(general
		(thickness 1.711)
		(legacy_teardrops no)
	)
	(paper "A4")
	(title_block
		(title "Antmicro Baseboard for Jetson AGX Thor")
		(date "2026-02-18")
		(rev "1.1.0")
		(company "Antmicro Ltd")
		(comment 1 "www.antmicro.com")
		(comment 9 "footprints 532-533 of 1170")
	)
	(layers
		(0 "F.Cu" signal)
		(4 "In1.Cu" signal)
		(6 "In2.Cu" signal)
		(8 "In3.Cu" signal)
		(10 "In4.Cu" jumper)
		(12 "In5.Cu" signal)
		(14 "In6.Cu" signal)
		(16 "In7.Cu" signal)
		(18 "In8.Cu" signal)
		(2 "B.Cu" signal)
		(9 "F.Adhes" user "F.Adhesive")
		(11 "B.Adhes" user "B.Adhesive")
		(13 "F.Paste" user)
		(15 "B.Paste" user)
		(5 "F.SilkS" user "F.Silkscreen")
		(7 "B.SilkS" user "B.Silkscreen")
		(1 "F.Mask" user)
		(3 "B.Mask" user)
		(17 "Dwgs.User" user "User.Drawings")
		(19 "Cmts.User" user "User.Comments")
		(21 "Eco1.User" user "User.Eco1")
		(23 "Eco2.User" user "User.Eco2")
		(25 "Edge.Cuts" user)
		(27 "Margin" user)
		(31 "F.CrtYd" user "F.Courtyard")
		(29 "B.CrtYd" user "B.Courtyard")
		(35 "F.Fab" user)
		(33 "B.Fab" user)
	)
	(footprint "antmicro-footprints:C_0603_1608Metric_EIA"
		(layer "F.Cu")
		(at 143.774391 128.15 -90)
		(descr "Capacitor SMD 0603, IPC-7351 Density Level A")
		(tags "Capacitor 0603")
		(property "Reference" "C32"
			(at -3.4 0.574391 90)
			(layer "F.SilkS")
			(effects
				(font
					(size 0.7 0.7)
					(thickness 0.15)
				)
				(justify right top)
			)
		)
		(property "Value" "C_22u_16V_0603"
			(at -1.42757 1.770288 90)
			(layer "F.Fab")
			(effects
				(font
					(size 0.7 0.7)
					(thickness 0.15)
				)
				(justify right top)
			)
		)
		(property "Datasheet" "https://product.samsungsem.com/mlcc/CL10A226MO7JZN.do"
			(at 0 0 90)
			(layer "F.Fab")
			(hide yes)
			(effects
				(font
					(size 1.27 1.27)
					(thickness 0.15)
				)
			)
		)
		(property "Description" "SMD Multilayer Ceramic Capacitor"
			(at 0 0 90)
			(layer "F.Fab")
			(hide yes)
			(effects
				(font
					(size 1.27 1.27)
					(thickness 0.15)
				)
			)
		)
		(property "MPN" "CL10A226MO7JZNC"
			(at 0 0 270)
			(unlocked yes)
			(layer "F.Fab")
			(hide yes)
			(effects
				(font
					(size 1 1)
					(thickness 0.15)
				)
			)
		)
		(property "Manufacturer" "Samsung Electro-Mechanics"
			(at 0 0 270)
			(unlocked yes)
			(layer "F.Fab")
			(hide yes)
			(effects
				(font
					(size 1 1)
					(thickness 0.15)
				)
			)
		)
		(property "License" "Apache-2.0"
			(at 0 0 270)
			(unlocked yes)
			(layer "F.Fab")
			(hide yes)
			(effects
				(font
					(size 1 1)
					(thickness 0.15)
				)
			)
		)
		(property "Author" "Antmicro"
			(at 0 0 270)
			(unlocked yes)
			(layer "F.Fab")
			(hide yes)
			(effects
				(font
					(size 1 1)
					(thickness 0.15)
				)
			)
		)
		(property "Val" "22u"
			(at 0 0 270)
			(unlocked yes)
			(layer "F.Fab")
			(hide yes)
			(effects
				(font
					(size 1 1)
					(thickness 0.15)
				)
			)
		)
		(property "Voltage" "16V"
			(at 0 0 270)
			(unlocked yes)
			(layer "F.Fab")
			(hide yes)
			(effects
				(font
					(size 1 1)
					(thickness 0.15)
				)
			)
		)
		(property "Dielectric" ""
			(at 0 0 270)
			(unlocked yes)
			(layer "F.Fab")
			(hide yes)
			(effects
				(font
					(size 1 1)
					(thickness 0.15)
				)
			)
		)
		(property "Public" "False"
			(at 0 0 270)
			(unlocked yes)
			(layer "F.Fab")
			(hide yes)
			(effects
				(font
					(size 1 1)
					(thickness 0.15)
				)
			)
		)
		(component_classes
			(class "DCDC_1V8")
		)
		(sheetname "/DCDC/")
		(sheetfile "dcdc.kicad_sch")
		(attr smd)
		(fp_line
			(start -0.15 0.55)
			(end 0.15 0.55)
			(stroke
				(width 0.15)
				(type solid)
			)
			(layer "F.SilkS")
		)
		(fp_line
			(start -0.15 -0.55)
			(end 0.15 -0.55)
			(stroke
				(width 0.15)
				(type solid)
			)
			(layer "F.SilkS")
		)
		(fp_rect
			(start -1.25 -0.65)
			(end 1.25 0.65)
			(stroke
				(width 0.05)
				(type solid)
			)
			(fill no)
			(layer "F.CrtYd")
		)
		(fp_rect
			(start -0.8 -0.45)
			(end 0.8 0.45)
			(stroke
				(width 0.15)
				(type solid)
			)
			(fill no)
			(layer "F.Fab")
		)
		(fp_text user "${REFERENCE}"
			(at -1.682 3.895 90)
			(layer "F.Fab")
			(effects
				(font
					(size 0.7 0.7)
					(thickness 0.15)
				)
				(justify right top)
			)
		)
		(fp_text user "Author: Antmicro"
			(at -1.682 4.894 90)
			(layer "F.Fab")
			(effects
				(font
					(size 0.7 0.7)
					(thickness 0.15)
				)
				(justify right top)
			)
		)
		(fp_text user "License: Apache-2.0"
			(at -1.682 5.895 90)
			(layer "F.Fab")
			(effects
				(font
					(size 0.7 0.7)
					(thickness 0.15)
				)
				(justify right top)
			)
		)
		(pad "1" smd roundrect
			(at -0.7 0 270)
			(size 0.8 1.1)
			(layers "F.Cu" "F.Mask" "F.Paste")
			(roundrect_rratio 0.2)
			(net 1 "GND")
			(pintype "passive")
		)
		(pad "2" smd roundrect
			(at 0.7 0 270)
			(size 0.8 1.1)
			(layers "F.Cu" "F.Mask" "F.Paste")
			(roundrect_rratio 0.2)
			(net 5 "+5V")
			(pintype "passive")
		)
	)
	(footprint "antmicro-footprints:MLP44-24L_4x4x0.75mm"
		(layer "F.Cu")
		(at 126.769212 61.55 -90)
		(property "Reference" "U75"
			(at -3.17 -2.480788 0)
			(layer "F.SilkS")
			(effects
				(font
					(size 0.7 0.7)
					(thickness 0.15)
				)
				(justify right top)
			)
		)
		(property "Value" "SIC437AED-T1-GE3"
			(at -2.7 3.6 90)
			(layer "F.Fab")
			(effects
				(font
					(size 0.7 0.7)
					(thickness 0.15)
				)
				(justify right top)
			)
		)
		(property "Datasheet" "https://www.vishay.com/docs/75921/sic437.pdf"
			(at 0 0 90)
			(layer "F.Fab")
			(hide yes)
			(effects
				(font
					(size 1.27 1.27)
					(thickness 0.15)
				)
			)
		)
		(property "Description" "DC/DC Buck Step Down Regulator Adjustable, 4.5-28V In, 0.6V to 20V/12A Out, 1MHz, PowerPAK MLP44-24"
			(at 0 0 90)
			(layer "F.Fab")
			(hide yes)
			(effects
				(font
					(size 1.27 1.27)
					(thickness 0.15)
				)
			)
		)
		(property "Manufacturer" "Vishay"
			(at 0 0 270)
			(unlocked yes)
			(layer "F.Fab")
			(hide yes)
			(effects
				(font
					(size 1 1)
					(thickness 0.15)
				)
			)
		)
		(property "MPN" "SIC437AED-T1-GE3"
			(at 0 0 270)
			(unlocked yes)
			(layer "F.Fab")
			(hide yes)
			(effects
				(font
					(size 1 1)
					(thickness 0.15)
				)
			)
		)
		(property "Author" "Antmicro"
			(at 0 0 270)
			(unlocked yes)
			(layer "F.Fab")
			(hide yes)
			(effects
				(font
					(size 1 1)
					(thickness 0.15)
				)
			)
		)
		(property "License" "Apache-2.0"
			(at 0 0 270)
			(unlocked yes)
			(layer "F.Fab")
			(hide yes)
			(effects
				(font
					(size 1 1)
					(thickness 0.15)
				)
			)
		)
		(sheetname "/DCDC/")
		(sheetfile "dcdc.kicad_sch")
		(attr smd)
		(net_tie_pad_groups "1,2,26" "3,4,27" "5,6,7,8,9")
		(fp_line
			(start -2.11 2.11)
			(end -2.11 1.39)
			(stroke
				(width 0.15)
				(type solid)
			)
			(layer "F.SilkS")
		)
		(fp_line
			(start -1.89 2.11)
			(end -2.11 2.11)
			(stroke
				(width 0.15)
				(type solid)
			)
			(layer "F.SilkS")
		)
		(fp_line
			(start 1.44 2.11)
			(end 2.11 2.11)
			(stroke
				(width 0.15)
				(type solid)
			)
			(layer "F.SilkS")
		)
		(fp_line
			(start 2.11 2.11)
			(end 2.11 1.84)
			(stroke
				(width 0.15)
				(type solid)
			)
			(layer "F.SilkS")
		)
		(fp_line
			(start -2.11 -1.38)
			(end -2.11 -2.1)
			(stroke
				(width 0.15)
				(type solid)
			)
			(layer "F.SilkS")
		)
		(fp_line
			(start -1.89 -2.1)
			(end -2.11 -2.1)
			(stroke
				(width 0.15)
				(type solid)
			)
			(layer "F.SilkS")
		)
		(fp_line
			(start 1.89 -2.11)
			(end 2.11 -2.11)
			(stroke
				(width 0.15)
				(type solid)
			)
			(layer "F.SilkS")
		)
		(fp_line
			(start 2.11 -2.11)
			(end 2.11 -1.69)
			(stroke
				(width 0.15)
				(type solid)
			)
			(layer "F.SilkS")
		)
		(fp_circle
			(center -2.25 -1.15)
			(end -2.2 -1.15)
			(stroke
				(width 0.15)
				(type solid)
			)
			(fill yes)
			(layer "F.SilkS")
		)
		(fp_line
			(start -2.55 2.55)
			(end -2.55 -2.55)
			(stroke
				(width 0.05)
				(type solid)
			)
			(layer "F.CrtYd")
		)
		(fp_line
			(start 2.55 2.55)
			(end -2.55 2.55)
			(stroke
				(width 0.05)
				(type solid)
			)
			(layer "F.CrtYd")
		)
		(fp_line
			(start -2.55 -2.55)
			(end 2.55 -2.55)
			(stroke
				(width 0.05)
				(type solid)
			)
			(layer "F.CrtYd")
		)
		(fp_line
			(start 2.55 -2.55)
			(end 2.55 2.55)
			(stroke
				(width 0.05)
				(type solid)
			)
			(layer "F.CrtYd")
		)
		(fp_line
			(start -2 2)
			(end 2 2)
			(stroke
				(width 0.15)
				(type solid)
			)
			(layer "F.Fab")
		)
		(fp_line
			(start 2 2)
			(end 2 -2)
			(stroke
				(width 0.15)
				(type solid)
			)
			(layer "F.Fab")
		)
		(fp_line
			(start -2 -1)
			(end -2 2)
			(stroke
				(width 0.15)
				(type solid)
			)
			(layer "F.Fab")
		)
		(fp_line
			(start -1 -2)
			(end -2 -1)
			(stroke
				(width 0.15)
				(type solid)
			)
			(layer "F.Fab")
		)
		(fp_line
			(start 2 -2)
			(end -1 -2)
			(stroke
				(width 0.15)
				(type solid)
			)
			(layer "F.Fab")
		)
		(fp_text user "License: Apache-2.0"
			(at -2.7 5.6 90)
			(layer "F.Fab")
			(effects
				(font
					(size 0.7 0.7)
					(thickness 0.15)
				)
				(justify right top)
			)
		)
		(fp_text user "${REFERENCE}"
			(at -2.7 6.8 90)
			(layer "F.Fab")
			(effects
				(font
					(size 0.7 0.7)
					(thickness 0.15)
				)
				(justify right top)
			)
		)
		(fp_text user "Author: Antmicro"
			(at -2.7 8 90)
			(layer "F.Fab")
			(effects
				(font
					(size 0.7 0.7)
					(thickness 0.15)
				)
				(justify right top)
			)
		)
		(pad "1" smd roundrect
			(at -1.94 -0.825)
			(size 0.3 0.725)
			(layers "F.Cu" "F.Mask" "F.Paste")
			(roundrect_rratio 0.25)
			(net 13 "VCC")
			(pinfunction "V_{IN}")
			(pintype "power_in")
		)
		(pad "2" smd roundrect
			(at -1.94 -0.375)
			(size 0.3 0.725)
			(layers "F.Cu" "F.Mask" "F.Paste")
			(roundrect_rratio 0.25)
			(net 13 "VCC")
			(pinfunction "V_{IN}")
			(pintype "passive")
		)
		(pad "3" smd roundrect
			(at -1.94 0.525)
			(size 0.3 0.725)
			(layers "F.Cu" "F.Mask" "F.Paste")
			(roundrect_rratio 0.25)
			(net 1 "GND")
			(pinfunction "P_{GND}")
			(pintype "passive")
		)
		(pad "4" smd roundrect
			(at -1.94 0.975)
			(size 0.3 0.725)
			(layers "F.Cu" "F.Mask" "F.Paste")
			(roundrect_rratio 0.25)
			(net 1 "GND")
			(pinfunction "P_{GND}")
			(pintype "passive")
		)
		(pad "5" smd custom
			(at -1.475 1.94 270)
			(size 0.3 0.3)
			(layers "F.Cu" "F.Mask" "F.Paste")
			(net 1297 "/DCDC/5V_{AON}_SW")
			(pinfunction "SW")
			(pintype "passive")
			(options
				(clearance outline)
				(anchor circle)
			)
			(primitives
				(gr_poly
					(pts
						(xy -0.15 -0.2875) (xy -0.144291 -0.316201) (xy -0.128033 -0.340533) (xy -0.103701 -0.356791)
						(xy -0.075 -0.3625) (xy 0.075 -0.3625) (xy 0.103701 -0.356791) (xy 0.128033 -0.340533) (xy 0.144291 -0.316201)
						(xy 0.15 -0.2875) (xy 0.15 0.2875) (xy 0.144291 0.316201) (xy 0.128033 0.340533) (xy 0.103701 0.356791)
						(xy 0.075 0.3625) (xy -0.075 0.3625) (xy -0.103701 0.356791) (xy -0.128033 0.340533) (xy -0.144291 0.316201)
						(xy -0.15 0.2875)
					)
					(width 0)
					(fill yes)
				)
				(gr_poly
					(pts
						(xy -0.15 -0.3625) (xy 2.2 -0.3625) (xy 2.2 -0.0875) (xy -0.15 -0.0875)
					)
					(width 0)
					(fill yes)
				)
			)
		)
		(pad "6" smd roundrect
			(at -1.025 1.94 270)
			(size 0.3 0.725)
			(layers "F.Cu" "F.Mask" "F.Paste")
			(roundrect_rratio 0.25)
			(net 1297 "/DCDC/5V_{AON}_SW")
			(pinfunction "SW")
			(pintype "passive")
		)
		(pad "7" smd roundrect
			(at -0.575 1.94 270)
			(size 0.3 0.725)
			(layers "F.Cu" "F.Mask" "F.Paste")
			(roundrect_rratio 0.25)
			(net 1297 "/DCDC/5V_{AON}_SW")
			(pinfunction "SW")
			(pintype "passive")
		)
		(pad "8" smd roundrect
			(at 0.125 1.94 270)
			(size 0.3 0.725)
			(layers "F.Cu" "F.Mask" "F.Paste")
			(roundrect_rratio 0.25)
			(net 1297 "/DCDC/5V_{AON}_SW")
			(pinfunction "SW")
			(pintype "passive")
		)
		(pad "9" smd roundrect
			(at 0.575 1.94 270)
			(size 0.3 0.725)
			(layers "F.Cu" "F.Mask" "F.Paste")
			(roundrect_rratio 0.25)
			(net 1297 "/DCDC/5V_{AON}_SW")
			(pinfunction "SW")
			(pintype "passive")
		)
		(pad "10" smd roundrect
			(at 1.025 1.935 270)
			(size 0.3 0.725)
			(layers "F.Cu" "F.Mask" "F.Paste")
			(roundrect_rratio 0.25)
			(net 1326 "unconnected-(U75-GL-Pad10)_1")
			(pinfunction "GL")
			(pintype "passive+no_connect")
		)
		(pad "11" smd roundrect
			(at 1.94 1.425)
			(size 0.3 0.725)
			(layers "F.Cu" "F.Mask" "F.Paste")
			(roundrect_rratio 0.25)
			(net 1327 "unconnected-(U75-GL-Pad10)_2")
			(pinfunction "GL")
			(pintype "passive+no_connect")
		)
		(pad "12" smd roundrect
			(at 1.94 0.975)
			(size 0.3 0.725)
			(layers "F.Cu" "F.Mask" "F.Paste")
			(roundrect_rratio 0.25)
			(net 1275 "/DCDC/5V_{AON}_VDRV")
			(pinfunction "V_{DRV}")
			(pintype "passive")
		)
		(pad "13" smd roundrect
			(at 1.94 0.525)
			(size 0.3 0.725)
			(layers "F.Cu" "F.Mask" "F.Paste")
			(roundrect_rratio 0.25)
			(net 1 "GND")
			(pinfunction "P_{GND}")
			(pintype "power_in")
		)
		(pad "14" smd roundrect
			(at 1.94 0.075)
			(size 0.3 0.725)
			(layers "F.Cu" "F.Mask" "F.Paste")
			(roundrect_rratio 0.25)
			(net 246 "/SoM_Power/~{VDDIN_PWR_BAD}")
			(pinfunction "P_{GOOD}")
			(pintype "output")
		)
		(pad "15" smd roundrect
			(at 1.94 -0.375)
			(size 0.3 0.725)
			(layers "F.Cu" "F.Mask" "F.Paste")
			(roundrect_rratio 0.25)
			(net 1274 "/DCDC/5V_{AON}_VDD")
			(pinfunction "V_{DD}")
			(pintype "passive")
		)
		(pad "16" smd roundrect
			(at 1.94 -0.825)
			(size 0.3 0.725)
			(layers "F.Cu" "F.Mask" "F.Paste")
			(roundrect_rratio 0.25)
			(net 1 "GND")
			(pinfunction "A_{GND}")
			(pintype "power_in")
		)
		(pad "17" smd roundrect
			(at 1.94 -1.275)
			(size 0.3 0.725)
			(layers "F.Cu" "F.Mask" "F.Paste")
			(roundrect_rratio 0.25)
			(net 1308 "/DCDC/5V_{AON}_FB")
			(pinfunction "FB")
			(pintype "passive")
		)
		(pad "18" smd roundrect
			(at 1.475 -1.94 270)
			(size 0.3 0.725)
			(layers "F.Cu" "F.Mask" "F.Paste")
			(roundrect_rratio 0.25)
			(net 1278 "/DCDC/5V_{AON}_OUT")
			(pinfunction "V_{OUT}")
			(pintype "passive")
		)
		(pad "19" smd roundrect
			(at 1.025 -1.94 270)
			(size 0.3 0.725)
			(layers "F.Cu" "F.Mask" "F.Paste")
			(roundrect_rratio 0.25)
			(net 1305 "/DCDC/5V_{AON}_EN")
			(pinfunction "EN")
			(pintype "input")
		)
		(pad "20" smd roundrect
			(at 0.575 -1.94 270)
			(size 0.3 0.725)
			(layers "F.Cu" "F.Mask" "F.Paste")
			(roundrect_rratio 0.25)
			(net 1307 "/DCDC/5V_{AON}_MODE2")
			(pinfunction "MODE2")
			(pintype "input")
		)
		(pad "21" smd roundrect
			(at 0.125 -1.94 270)
			(size 0.3 0.725)
			(layers "F.Cu" "F.Mask" "F.Paste")
			(roundrect_rratio 0.25)
			(net 1306 "/DCDC/5V_{AON}_MODE1")
			(pinfunction "MODE1")
			(pintype "input")
		)
		(pad "22" smd roundrect
			(at -0.575 -1.94 270)
			(size 0.3 0.725)
			(layers "F.Cu" "F.Mask" "F.Paste")
			(roundrect_rratio 0.25)
			(net 13 "VCC")
			(pinfunction "V_{IN}")
			(pintype "passive")
		)
		(pad "23" smd roundrect
			(at -1.025 -1.94 270)
			(size 0.3 0.725)
			(layers "F.Cu" "F.Mask" "F.Paste")
			(roundrect_rratio 0.25)
			(net 1276 "/DCDC/5V_{AON}_BOOT")
			(pinfunction "BOOT")
			(pintype "passive")
		)
		(pad "24" smd roundrect
			(at -1.475 -1.94 270)
			(size 0.3 0.725)
			(layers "F.Cu" "F.Mask" "F.Paste")
			(roundrect_rratio 0.25)
			(net 1277 "/DCDC/5V_{AON}_PHASE")
			(pinfunction "PHASE")
			(pintype "passive")
		)
		(pad "25" smd rect
			(at 0.49 -0.75 90)
			(size 1.575 1.05)
			(layers "F.Cu" "F.Mask" "F.Paste")
			(net 1 "GND")
			(pinfunction "A_{GND}")
			(pintype "passive")
		)
		(pad "26" smd rect
			(at -1.175 -0.750001 90)
			(size 1.15 1.05)
			(layers "F.Cu" "F.Mask" "F.Paste")
			(net 13 "VCC")
			(pinfunction "V_{IN}")
			(pintype "passive")
		)
		(pad "27" smd custom
			(at -0.75 0.775 270)
			(size 1 1)
			(layers "F.Cu" "F.Mask" "F.Paste")
			(net 1 "GND")
			(pinfunction "P_{GND}")
			(pintype "passive")
			(options
				(clearance outline)
				(anchor rect)
			)
			(primitives
				(gr_poly
					(pts
						(xy -1 0.5) (xy -1 -0.7) (xy 1.825 -0.7) (xy 1.825 -0.245) (xy 1.175 -0.245) (xy 1.175 0.5)
					)
					(width 0)
					(fill yes)
				)
			)
		)
		(pad "28" smd rect
			(at 0.985 0.99 90)
			(size 0.58 0.38)
			(layers "F.Cu" "F.Mask" "F.Paste")
			(net 1325 "unconnected-(U75-GL-Pad10)")
			(pinfunction "GL")
			(pintype "passive+no_connect")
		)
	)
)
